 
 
 
Open CloudServer  
chassis specification  
V1.0 
 
Authors: 
Mark Shaw, Director of Hardware Engineering, Microsoft 
Martin Goldstein, Principal Systems Architect, Microsoft 
  


 
2    January 28, 2014 
 
1 Revision History 
 
Date Name Description 
1/28/2014  Version 1.0 
   
   
   
   
   
   
   
 
 
 
  



Open Compute Project  Open CloudServer chassis specification  
http://opencompute.org    3 
 
© 2014 Microsoft Corporation. 
 
As of January 28, 2014, the following persons or entities have made this Specification available under 
the Open Web Foundation Final Specification Agreement (OWFa 1.0), which is available at 
http://www.openwebfoundation.org/legal/the-owf-1-0-agreements/owfa-1-0 Microsoft Corporation.  
You can review the signed copies of the Open Web Foundation Agreement Version 1.0 for this 
Specification at http://opencompute.org/licensing/, which may also include additional parties to those 
listed above. 
Your use of this Specification may be subject to other third party rights. THIS SPECIFICATION IS 
PROVIDED "AS IS." The contributors expressly disclaim any warranties (express, implied, or otherwise), 
including implied warranties of merchantability, noninfringement, fitness for a particular purpose, or title, 
related to the Specification. The entire risk as to implementing or otherwise using the Specification is 
assumed by the Specification implementer and user. IN NO EVENT WILL ANY PARTY BE LIABLE TO ANY 
OTHER PARTY FOR LOST PROFITS OR ANY FORM OF INDIRECT, SPECIAL, INCIDENTAL, OR 
CONSEQUENTIAL DAMAGES OF ANY CHARACTER FROM ANY CAUSES OF ACTION OF ANY KIND WITH 
RESPECT TO THIS SPECIFICATION OR ITS GOVERNING AGREEMENT, WHETHER BASED ON BREACH OF 
CONTRACT, TORT (INCLUDING NEGLIGENCE), OR OTHERWISE, AND WHETHER OR NOT THE OTHER 
PARTY HAS BEEN ADVISED OF THE POSSIBILITY OF SUCH DAMAGE. 
CONTRIBUTORS AND LICENSORS OF THIS SPECIFICATION MAY HAVE MENTIONED CERTAIN 
TECHNOLOGIES THAT ARE MERELY REFERENCED WITHIN THIS SPECIFICATION AND NOT LICENSED 
UNDER THE OWF CLA OR OWFa. THE FOLLOWING IS A LIST OF MERELY REFERENCED TECHNOLOGY: 
INTELLIGENT PLATFORM MANAGEMENT INTERFACE (IPMI), I2C TRADEMARK OF PHILLIPS 
SEMICONDUCTOR. IMPLEMENTATION OF THESE TECHNOLOGIES MAY BE SUBJECT TO THEIR OWN 
LEGAL TERMS.  



 
4    January 28, 2014 
 
2 Scope 
This document provides the technical specifications for the design of the Open 
CloudServer system chassis. 
3 Contents 
1 Revision History ......................................................................................................................... 2 
2 Scope ......................................................................................................................................... 4 
3 Contents .................................................................................................................................... 4 
4 Overview.................................................................................................................................... 5 
5 Chassis Specification .................................................................................................................. 8 
5.1 Chassis Physical Specification ....................................................................................... 8 
5.2 Power Delivery ........................................................................................................... 15 
5.3 Tray Specifications ...................................................................................................... 17 
5.4 Blade Numbering ........................................................................................................ 27 
6 Cooling System Specifications ................................................................................................. 27 
6.1 Thermal Design Considerations .................................................................................. 28 
6.2 Blade Impedance ........................................................................................................ 28 
6.3 Fan System Performance ........................................................................................... 32 
6.4 Fan Speed Control ...................................................................................................... 34 
6.5 Fan Failure .................................................................................................................. 38 
6.6 Thermal Considerations for the Blade ....................................................................... 39 
7 Chassis Power .......................................................................................................................... 40 
8 Operating Environment ........................................................................................................... 41 
9 Safety and Compliance Documentation .................................................................................. 41 
10 Shock and Vibration Requirements ......................................................................................... 42 
11 Appendix: Commonly Used Acronyms .................................................................................... 46 
  



Open Compute Project  Open CloudServer chassis specification  
http://opencompute.org    5 
 
4 Overview 
The Open CloudServer system is a fully integrated rack of servers and IT equipment 
that is highly optimized and streamlined for large, web-scale deployments. The 
system is intended to support at least two generations of servers to minimize the 
detailed, time-consuming, and expensive process of setting up networking and 
infrastructure in a server deployment.  
The system utilizes an off-the-shelf (OTS) commodity rack that is loaded with up to 
four modular chassis, each with trays, power supplies, power distribution, rack 
management, system fans, and two side-walls, as shown in Figure 1. 
 
Figure 1. System overview 
Blades are highly configurable, and are usually compute blades or storage “just a 
bunch of disks” (JBOD) blades.  
Figure 2 shows an example of a blade. 


 
6    January 28, 2014 
 
 
Figure 2. Blade assembly 
Each chassis supports 12 rack unit (U or 1U, each 19" wide and 1.75" tall) trays that 
house up to 24 individual blades (two blades per tray). Blades can be designed to 
use the full width of the tray. It is also possible to use multiple rack units to house a 
single tall blade, with certain restrictions. 
Power and management are distributed through the chassis power distribution 
backplane (PDB). The power distribution backplane attaches vertically to the 
individual trays on one side and to the power supply unit (PSU) on the other side. 
This arrangement reduces the current carrying requirements of the distribution 
board, eliminates cabling, and reduces costs. 
Figure 3 shows the chassis components. 


Open Compute Project  Open CloudServer chassis specification  
http://opencompute.org    7 
 
 
Figure 3. Chassis components 
Power is distributed from the power supply units through the PDB to the trays and 
blades. Management signals are routed between the Chassis Manager and the blades 
through the PDB and tray via serial communication signals and discrete on/off 
signals. 
The tray backplane carries power, management, and high-speed I/O through a blind-
mate connection to the blade as seen in Figure 4. The Ethernet (10 Gigabit) 
networking and serial-attached small computer system interface (SAS) storage signals 
pass through the blind-mate connector and are routed to attachments at the rear of 
the chassis. The cables are routed through the rear of the chassis to networking 
equipment placed elsewhere. Note that running the cables through the rear of the 
blade eliminates the need to connect directly to the servers. Once provisioned, the 
network cabling should only be touched when a cable or switch fails. The type and 
number of networking switches depends on the specific deployment.  


 
8    January 28, 2014 
 
 
Figure 4. Chassis Trays 
5 Chassis Specification 
The following sections describe the chassis. 
The chassis is an assembly of interlocking components designed to be individually 
mounted to the rack. It provides structure and airflow to the blades and other 
electrical subsystems. 
5.1 Chassis Physical Specification 
The physical specifications for the chassis include the dimensions and a description 
of the guiding and latching features. 


Open Compute Project  Open CloudServer chassis specification  
http://opencompute.org    9 
 
5.1.1 Volumetric Specifications 
Figure 5 shows details of the chassis from the rear, and Figure 6 shows details of the 
chassis from the front. 
 
Figure 5. Chassis details, from the rear 
 
Figure 6. Chassis details, from the front 
The chassis is enclosed at the top and bottom of the rear airflow plenum to minimize 
recirculation and maximize blade cooling. The top of the chassis is also enclosed to 


 
10    January 28, 2014 
 
ensure that air passes through the blades. Note that airflow blanks are required for 
slots that are not occupied by blades. These blanks must be closed to airflow to 
avoid short-circuiting the adjacent blades. 
The following figures show the dimensions of the main system components: the 
chassis, the tray, and the blade. 
Figure 7 shows the dimensions of the chassis. 
 
Figure 7. Overall chassis dimensions (in mm) 
Figure 8 shows the dimensions of the tray. 
 
Figure 8. Overall tray dimensions (in mm) 
Figure 9 shows the overall dimensions of the blade. 


Open Compute Project  Open CloudServer chassis specification  
http://opencompute.org    11 
 
 
Figure 9. Overall blade dimensions (in mm) 
Figure 10 shows the chassis detailed dimensions. This is the volume the fully 
assembled chassis occupies within the rack.  
  
Figure 10. Chassis volumetric requirements (0U plenum removed for clarity) 


 
12    January 28, 2014 
 
There is a separate inlet air plenum for the power supplies routed along the “0U” 
space of the rack. Features in the side plenum help seal this inlet when the chassis is 
secured in the rack so that the air from the hot aisle cannot enter the power 
supplies, as shown in Figure 11. 
 
Figure 11. Rear rack column seal 
The chassis can accommodate a rack column spacing of 736.6mm. The columns must 
use 9.5mm square holes. Air for the power supplies is drawn through the columns, as 
shown in Figure 12. 
 


Open Compute Project  Open CloudServer chassis specification  
http://opencompute.org    13 
 
Figure 12. Column air flow passage 
Sliding sub-assemblies are keyed to ensure that they are connected correctly, unless 
incorrect installation causes no damage. For example, the trays and blades are keyed 
so they will not be installed upside down; power supplies are not keyed because they 
cause no damage if installed upside down. 
Note that if the blades will be shipped within the chassis, additional braces are 
required for support. The braces transfer forces directly to the rack columns and 
provide load-bearing support for the front of the blades. 
Note also that the chassis is not intended to provide electromagnetic interference 
(EMI) containment. 
5.1.2 Latching Features and Fasteners 
Latches, as well as thumb screws and other components used to lock, unlock, or 
remove a subassembly from the chassis, are colored blue (Pantone code 285 C blue) 
to make them easy to identify. In the chassis, these latching features include: 
 Fan door securing features 
 Power supply unit latch covers 
 Chassis Manager module securing features 
To avoid confusion when removing a blade, the tray release wire form loops should 
not be colored blue. 
Fasteners that require Torx drivers can be used to secure the chassis to the rack. 
Assembling the trays, blades, power supplies, and the fan tray does not require tools. 
5.1.3 Power Distribution Unit Placement 
Figure 13 shows the notch included in the chassis to make the power distribution 
unit (PDU) in the 1200mm rack replaceable. (Note that other figures in this document 
do not yet reflect this recent change.) 



 
14    January 28, 2014 
 
 
Figure 13. Notched chassis for PDU placement 
The chassis includes mounting holes to secure the PDU in the correct position, as 
shown in Figure 14 (this figure to be used for reference only). 
 


Open Compute Project  Open CloudServer chassis specification  
http://opencompute.org    15 
 
Figure 14. PDU mounting strip 
5.2 Power Delivery 
The chassis delivers power to the trays through the power distribution backplane 
printed circuit board assembly (PCBA). The PDB accepts six 39.3mm x 86.3mm x 
197.6mm commodity off-the-shelf (COTS) power supply units to keep costs low. Six 
PSUs on a shared power backplane provides nearly ideal phase balancing of three-
phase AC inputs, which allows a higher utilization of the incoming power. 
Note that most of the weight of the power supplies is supported by the chassis, not 
by the power connector. 
5.2.1 Power Distribution Backplane 
The power distribution backplane provides power to each tray assembly, to the fan 
assembly, and to the Chassis Manager card.  
The power distribution backplane also acts as the center point for chassis data 
communications, and includes the following cable connections: 
 Local area network (LAN) 1, 2 
 Serial COM 1, 2, 5, 6 
 Power control switch outputs 1, 2, 3 
 Chassis Manager power control input 
 Fan door power, control, and monitoring 
The power distribution backplane accepts 19 assemblies: 
 Chassis Manager 
 12 tray backplane connectors  
 Six power supply connectors 
Figure 15 shows details of the power distribution backplane. 



 
16    January 28, 2014 
 
 
Figure 15. Power distribution board  


Open Compute Project  Open CloudServer chassis specification  
http://opencompute.org    17 
 
5.2.2 PDB Interconnects 
Table 1 lists the power distribution board connections. 
Table 1. Power Distribution Board-to-Tray Backplane Connectors List  
Assembly 
mounting 
Assembly 
attachment Connector description  Manufacturing part number 
PDB  
J1-J6 
Power supply 
unit  
64 pin receptacle, vertical, two 
rows, 2.54mm pitch (FCI) 10046971-001LF 
PDB  
J7-J18 Tray backplane High-power connector (FCI) 10117936-003LF 
PDB  
J25, J26 
Chassis 
Manager 
Dual, 1.00mm pitch, PCI Express 
x16 connector, 164 circuits each 
(328 circuits total) 
(Amphenol) G630HAA15012EU 
PDB Fan assembly 20 pin connector, 2 rows, 4.2mm 
pitch (Molex) 39-28-1203 
PDB RJ45 RJ45 for serial port (Tyco) 5569284-1 
PDB RJ45 RJ45 for 1G LAN (Amphenol) G71B0250100EU 
PDB PDU/Chassis 
Manager Power switch control (Molex) 353030251 
 
5.3 Tray Specifications 
The following sections describe the trays.  
For service and debugging, the tray must be able to function in standalone mode 
(external to the chassis) for debugging. The tray can attach and receive power, 
Blade_EN, and serial signals without impacting cost or operation in production 
environments. The preferred method to attach to the tray is through headers that are 
not loaded for operation within the chassis. 
The physical specifications for the trays include the dimensions of the tray volume 
and a description of the guiding and latching features. 



 
18    January 28, 2014 
 
5.3.1 Volumetric Specifications 
Figure 16 shows the tray backplane and Figure 17 shows the tray cabling. 
 
Figure 16. Tray backplane 
 
 
Figure 17. Tray cabling 


Open Compute Project  Open CloudServer chassis specification  
http://opencompute.org    19 
 
The tray’s outer dimensions must not exceed those described, with all tolerances for 
different manufacturing methods (such as soft and hard tooling) accounted for; the 
tray’s interior must be able to accept a blade as described in Section 3.1: Volumetric 
Specifications of this specification. The tray mechanically interlocks to the power 
backplane support to minimize the load the connector must support.  
The chassis is designed to be installed into a rack that complies with the EIA-310-D 
standard (the current revision of the Electronic Industries Alliance standard for a 19” 
rack) without modification.  
Figure 18 describes the opening in the chassis that accepts the trays, as viewed from 
the front of the system.  
  
Figure 18. Interior tray opening chassis volumetric 
The chassis interior consists of a series of flanges that extend from the side walls to 
support the trays. A power distribution board is located at the rear of the opening, 
on the left side as viewed from the front, to transfer power from the bulk power 
supply units to the trays.  


 
20    January 28, 2014 
 
Figure 19 shows the tray volume as seen from the front, and defines the location of 
the tray supports as related to the power connector.  
A tray latch release is integrated into the chassis structure located on the left and 
right sides of the chassis opening.  
  
Figure 19. Interior tray opening volumetric detail 
Figure 20 shows a side view of the chassis. These dimensions are critical to the fit 
and function of the tray. 


Open Compute Project  Open CloudServer chassis specification  
http://opencompute.org    21 
 
 
Figure 20. Side view of chassis 
5.3.2 Guiding and Latching 
The chassis supports the tray on a series of ledges located on each side wall. These 
ledges are designed and manufactured to prevent metallic slivers from forming when 
the tray is inserted into the chassis. Shoulder pins are included in the chassis side 
walls to secure the walls of the tray during insertion and prevent the tray from 
sagging under the load of the blades. 
A pull-to-release spring latch is incorporated into the left-side and right-side panels 
to keep the tray in the chassis. Figure 21 shows a pull-to-release latch. Figure 20 
shows the dimensions of the latch. 
Notes:   
[1] Power connector surface 
end to hard stop on 
surface 
[2] Power connector surface 
end to tray load pin tip 
[3] Power connector surface 
end to tray latch holding 
surface 
 



 
22    January 28, 2014 
 
 
Figure 21. Example view of the push-to-release spring latch 
5.3.3 Tray Interconnect 
The tray provides the electrical interface to the blade, the PDB and external 
Networking and Storage cables. Figure 22 shows a top view of the tray features. 


Open Compute Project  Open CloudServer chassis specification  
http://opencompute.org    23 
 
 
Figure 22. Tray features, top view 
5.3.3.1 Tray-to-Cable Interconnects 
The tray backplane carries high-speed signals from the blade connector to the cable 
connectors in the rear of the system. All applicable connectors in the backplane are 
pinned out. Signal delivery is through either one tray SKU with the backplane using 
all connectors, or through multiple tray SKUs with only specific connectors loaded.  
Figure 23 shows the backplane and the connector signals (reference design shown). 



 
24    January 28, 2014 
 
 
Figure 23. Tray backplane cable interconnects  
5.3.3.2 Tray Connectors 
Table 2 lists the connectors used for the tray-to-blade and tray-to-cable electrical 
interfaces. 
Table 2. Tray-to-Blade and Tray-to-External Cable Electrical Interface Power/Network Distribution PCB 
Connectors List 
Assembly 
mounting 
Assembly 
attachment Connector description  Manufacturing part number 
Tray backplane Blade Power connector—AirMax  
Power receptacle—coplanar 2x2 (FCI)10052620-4555P00LF 
Tray backplane Blade 
Signal connector—three pair, 54 
contact, 2mm spacing, 19mm 
pitch, six-column press fit 
(FCI) 10053656-101LF 
Tray
Backplane
PDB
Blade N+12
SFP+ #2
SFP+ #1 Network 
Airmax
SAS 
AirmaxSAS #2
SAS #1
1Gb 1&2
Blade N
SFP+ #2
SFP+ #1 Network 
Airmax
SAS 
AirmaxSAS #2
SAS #1
1Gb 1&2



Open Compute Project  Open CloudServer chassis specification  
http://opencompute.org    25 
 
Assembly 
mounting 
Assembly 
attachment Connector description  Manufacturing part number 
Tray backplane Blade Guide pin— 10.8mm, right angle 
0° key (FCI) 10044366-101LF 
Tray backplane Cable Mini-serial-attached SCSI (mini-
SAS) 
Connector— (Molex) 75586-0009 
Cage— (Molex) FBRS200101 
(or equivalent) 
Tray backplane Cable  Small form-factor pluggable 
(SFP)+ 
Connector— (Tyco) 188247-1 
Cage —(Tyco) FBS2D00301 
(or equivalent) 
Tray backplane Cable  
Dual-panel jack RJ45 
(Unused in V1 implementation) 
(Tyco) 5569381-1  
(or equivalent) 
Figure 22 and Figure 23 show the placements of the connectors. Note that if a 
backplane or other design is used, functionally equivalent connectors must be 
specified and located within the described volume. 
Figure 24 shows the PDB connector used to mate with the TB gold fingers. 
 
Figure 24. Power connector pin out 
The power connector supports a maximum of 1,382W per tray (12V x 16 pins x 
9A/pin x 80 percent derating). The power per rack unit is limited to 600W. This 
connector allows a future 2U server to consume 1200W. 
Table 3 shows the pinout for the signal part of the power connector on the tray 
backplane. 


 
26    January 28, 2014 
 
Table 3. Pinout for Signal Portion of the Power Connector on the Tray Backplane 
Pin Signal name Tray input/output Definition 
S1 Node1_TXD Input Node 1 serial input 
S2 Node1_RXD  Output Node 1 serial output 
S3 Node1_EN Input Node 1 power enable 
S4 Node2_EN Input Node 2 power enable 
S5 Node2_TXD Input Node 2 serial input 
S6 Node2_RXD Output Node 2 serial output 
S12 Node3_TXD Input Node 3 serial input 
S11 Node3_RXD Output Node 3 serial output 
S10 Node3_EN Input Node 3 power enable 
S9 Node4_EN Input Node 4 power enable 
S8 Node4_TXD Input Node 4 serial input 
S7 Node4_RXD Output Node 4 serial output 
Table 4 shows the power connector pin-out. 
Table 4. Pinout for Power Connector 
Pin Signal name Capacity 
P1 through P4 12V return 9A per pin 
P5 through P8 12V return 9A per pin 
P9 through P12 12V supply 9A per pin 
P13 through P16 12V supply 9A per pin 
P17 through P20 12V supply 9A per pin 
P21 through P24 12V supply 9A per pin 
P25 through P28 12V return 9A per pin 
P29 through P32 12V return 9A per pin 



Open Compute Project  Open CloudServer chassis specification  
http://opencompute.org    27 
 
5.4 Blade Numbering 
Blades are hard wired through the management subsystem to specific positions. This 
ensures that there is zero ambiguity for service or networking. Table 5 lists the blade 
numbers, with both front and rear views. 
 
Table 5. Blade Numbers 
U number Blades when viewed from front Blades when viewed from rear 
12 12 24 24 12 
11 11 23 23 11 
10 10 22 22 10 
9 9 21 21 9 
8 8 20 20 8 
7 7 19 19 7 
6 6 18 18 6 
5 5 17 17 5 
4 4 16 16 4 
3 3 15 15 3 
2 2 14 14 2 
1 1 13 13 1 
6 Cooling System Specifications 
The following sections describe the cooling system. 
Cooling for the blades is provided by six 140mm x 140mm x 38mm shared rear-
system fans mounted on the chassis. The fans are configured in an N+1 
arrangement; if a fan fails, the system can maintain the required cooling with the 
remaining fans. 
Power supplies are cooled by their internal fans and supplied with fresh air by a 
channel along the side of the server. 



 
28    January 28, 2014 
 
6.1 Thermal Design Considerations 
The fans provide all of the cooling and airflow required by the blades; it is therefore 
critical to design the blades so that all of their components are sufficiently cooled by 
the system fans. 
The cooling system was designed so that the fans consume the least amount of 
power possible while maintaining the necessary cooling. Thermal efficiency is 
typically reported as temperature rise across the blade (∆ T), which is equal to the 
difference between the average exhaust temperature and the average inlet 
temperature. For a given blade power consumption, a higher ∆ T means that the fans 
are operating at a lower speed and consuming less power driving up the overall 
system efficiency; in other words, a slower fan speed means lower power 
consumption, which means a higher rise in temperature. 
The blade server exhaust temperature directly reflects the hot-aisle temperature of a 
data center. The blade thermal-control system should include an exhaust 
temperature sensor (or other method to monitor the blade outlet temperature) to 
ensure that the system meets data center requirements. 
6.2 Blade Impedance 
The system airflow must provide sufficient cooling for an 18OC temperature rise for 
600W thermal design power (TDP) per rack unit (equivalent to 300W TDP per blade) 
at the expected end-of-life of the fan.  
Figure 25 shows the airflow impedance the blades must meet to achieve this 
required performance.  



Open Compute Project  Open CloudServer chassis specification  
http://opencompute.org    29 
 
 
Figure 25. Blade flow specification: allowable blade pressure/flow curve 
Blade impedance within 25 percent of the target ensures that all blades within the 
system receive sufficient airflow. Blade impedance that is too low results in higher 
airflow through the blade and lower airflow through the other blades in the system. 
Impedance that is too high results in a lower airflow through the blade.  
It is possible to increase the blade impedance if the blade is designed for a TDP less 
than 300W; however, simulation and testing should be used to verify that there is no 
negative impact on other blades in the system and that the airflow for the entire 
system is sufficient. The following example for a blade with a TDP rating of 200W 
shows the preferred method for modifying the blade impedance curve.  
1. Determine the flow rate required to meet  the ΔT target by using the following 
equation.  
𝑄̇2 = 𝑇𝐷𝑃2 ∗ [ 𝑄̇1
𝑇𝐷𝑃1
] = 520𝐶𝐹𝑀 
𝑇𝐷𝑃1= Thermal design power of the reference system (7200W) 
𝑄̇1= Flow rate of the nominal target curve of the system (780CFM) 
0.0
0.1
0.2
0.3
0.4
0.5
0.6
0 5 10 15 20 25 30 35 40
Blade Pressure Drop, "H2O
Blade Flow Rate, CFM
Blade Target Impedance
Allowable Blade Impedance window, +/- 25%)



 
30    January 28, 2014 
 
𝑇𝐷𝑃2= Expected blade thermal design power (4800W) 
𝑄̇2= Required flow rate of the modified blades in the system 
This equation provides the target flow rate for the lower-powered blade at 
maximum flow rate. The calculations must be based on the entire system flow to 
resolve the difference between the number of fans and the number of blades. 
2. Using the end-of-life fan performance curve, find the equivalent pressure 
required to meet the flow rate (𝑄̇2). This can be determined graphically or by 
interpolating the fan curve into an equation.  
The following equation is a polynomial interpolation of the fan curve:  
𝑃2 =  2.98764 ∗ 10−7𝑄̇ 2
2
 −  1.15085 ∗ 10−3𝑄̇ 2  +  9.4015 
𝑃2 =0.42”H2O 
𝑄̇2=520CFM 
𝑃2 = Required blade pressure at full fan speed for the lower-power blade 
3. Use the fan law relationships to determine the pressure and flow curves at 
reduced fan speeds. This involves calculating the fan curve at lower fan speeds 
and relating the maximum operating point determined in the previous step to 
the lower fan speed. 
𝑄̇𝑛 = 𝑄̇2 [2
𝑛
] 
𝑃𝑛 = 𝑃2 [2
𝑛
]
2
 
 2 = Full fan speed, 6600 RPM 
𝑄̇2 = 520CFM 
𝑃2 = 0.42”H2O 
𝑋𝑛 = n represents the fan speed of interest 
 



Open Compute Project  Open CloudServer chassis specification  
http://opencompute.org    31 
 
Table 6 shows the results of the calculations. 
Table 6. Calculation Results 
𝒏 
(in RPM) 
𝑸̇ 𝒏 
(in CFM) 
𝑷𝒏 
(in “H2O) 
500 39.62 0.00241 
935.7 74.14 0.008442 
1371 108.7 0.01813 
1807 143.2 0.03149 
2243 177.7 0.0485 
2679 212.2 0.06918 
3114 246.8 0.09351 
3550 281.3 0.1215 
3986 315.8 0.1532 
4421 350.3 0.1885 
4857 384.9 0.2275 
5293 419.4 0.2701 
5729 453.9 0.3164 
6164 488.4 0.3664 
6600 523 0.42 
Figure 26 shows the results are shown in graphical form. The curve for the individual 
blade is the flow result of the analysis divided by 24 blades. 



 
32    January 28, 2014 
 
 
Figure 26. Blade pressure/flow modification example showing expected system performance 
6.3 Fan System Performance 
Figure 27 shows an example of the performance of a fan system that can be used for 
modeling and prototyping. The example is based on the performance of the 140mm x 
140mm x 38mm fan system, with five full speed fans and one inactive fan at end-of-life. The 
graph gives the flow performance at the system level (for all fans in the plenum).
0
0.05
0.1
0.15
0.2
0.25
0.3
0.35
0.4
0.45
0 200 400 600 800 1000
Fan pressure, "H2O
Fan flow rate, CFM
Example 200W Blade
Impedance Curve
Standard Blade Target
Impedance Curve



Open Compute Project  Open CloudServer chassis specification  
http://opencompute.org    33 
 
 
Figure 27. System fan performance curve: expected performance for n fans 
To use this data, a designer should build a model or prototype of the chassis, 
including all pertinent flow restrictions. The designer should then add the appropriate 
number of blades, and use the N-curve in Figure 27 to evaluate blade thermal 
performance. 
Airflow blanks are required for slots that are not occupied by blades. These blanks 
should restrict airflow as much as possible to maximize flow performance to the 
blades within the chassis.  
The system is designed to permit a service operation in which the fan tray is rotated 
away from the chassis for up to five minutes. After five minutes, blade component 
temperatures might be high enough to cause a thermal shut down. (The precise time 
that the tray can remain open before shut down will be determined after extensive 
testing of prototype hardware.) 
0
0.1
0.2
0.3
0.4
0.5
0.6
0.7
0.8
0.9
1
0 200 400 600 800 1000 1200 1400
Fan pressure, "H2O
Fan flow rate, CFM



 
34    January 28, 2014 
 
6.4 Fan Speed Control 
The fans have variable speed capability; this lets the system drive the fans at speeds 
only as high as necessary to cool the components, minimizing power consumption, 
noise, and fan failures.  
6.4.1 Pulse-Width Modulation Input 
The blades exchange thermal information with the Chassis Manager through an 
intelligent platform management interface (IPMI). The first sensor value in the IPMI 
table is the pulse-width modulation (PWM) duty cycle fan speed, a value between 
the non-critical limits of 0 (fan off) and 100 (fan running at full speed). Note that the 
minimum fan speed is 20 percent of duty cycle to ensure that the fan has enough 
torque to maintain rotation. 
Using PWM signals simplifies the system-level control strategy and allows the system 
to be blade agnostic. Blades request their own fan speeds. The Chassis Manager 
polls each blade periodically for its fan flow rate request through a PWM signal, and 
then drives the fan speeds based on the highest request.  
Blades are responsible for monitoring all thermally critical component temperatures 
and determining an appropriate fan speed. A closed-loop method for monitoring 
temperature and adjusting speed requests is highly recommended. At minimum, a 
fan speed table based on measured inlet temperature is required, and the inlet and 
outlet temperatures of thermally critical components (such as processors, DIMMs, 
and PCHs) should be available through the IPMI interface. These sensors should have 
identification values other than 1 and should not have metadata limits.  
Table 7 lists important variables in fan control strategy.  
Table 7. Fan Control Variables 
Variable Value and description 
Target temperature band 
Used to control limits of processor temperature 
Upper = target temperature 
Lower = target temperature – 4OC 
Blade poll frequency 
Frequency of blade temperature requests 
10 seconds 



Open Compute Project  Open CloudServer chassis specification  
http://opencompute.org    35 
 
Variable Value and description 
Fan speed decrease hysteresis 
The amount of time the fan must wait between speed changes 
(prevents the fan speed from rising and falling too frequently) 
1 minute 
Altitude compensation Increase speed by 3.2 percent for every 1000 ft (304m) above sea 
level (see Figure 28) 
Active fan correction factor 
𝐷𝐶 = 𝐷𝐶𝑏𝑎𝑠𝑒 ∗ (5 𝑁𝑎𝑐𝑡𝑖𝑣𝑒⁄ ) 
𝐷𝐶 is the fan speed duty cycle requested by the Chassis Manager 
𝐷𝐶𝑏𝑎𝑠𝑒 is the base fan speed duty cycle before fan count and 
altitude correction 
𝑁𝑎𝑐𝑡𝑖𝑣𝑒 is the number of active system fans (if no fans have failed, 
this is six) 
(See Figure 29) 
6.4.2 Fan Speed Correction for Altitude 
Fan speed is increased by 3.2 percent for every 1000 ft (304m) above sea level. The 
location of the system must therefore be recorded during installation so that the 
correction can be made.  
Figure 28 shows an example of fan speed correction for altitude. 



 
36    January 28, 2014 
 
 
Figure 28. Example of altitude correction factor (non-critical limits: lower=15C ambient, upper=35C 
ambient)  
6.4.3 Fan Speed Correction for Fan Failures 
The Chassis Manager monitors the number of active fans and makes appropriate 
adjustments to the fan speed if a fan is detected to have failed (Section 4.5: Fan 
Failure provides more information about fan failure). A fan is considered to have 
failed if the tachometer speed returned to the Chassis Manager is below 20 percent 
of the requested speed for more than five minutes. 
Figure 29 shows an example of the fan failure correction factor. 


Open Compute Project  Open CloudServer chassis specification  
http://opencompute.org    37 
 
 
Figure 29. Example of an active fan count correction factor (non-critical limits: lower=15, upper=35) 
Note that fan failures trigger an alert so that the fan can be replaced (no action is 
required on the blade). 
6.4.4 Sensor Failure 
If a PWM signal from a specific blade is not detected or is determined to be 
unrealistic (less than 0 or more than 100), the blade is assigned a request of the 
minimum fan speed, and the speed requests from the other blades in the system will 
take priority.  
If there is only one blade is in the system and if the PWM signal is not present, the 
chassis will operate fans at the minimum speed. If blade activity forces a thermal 
shut-down under these conditions, the blade must be replaced or repaired.  
If the blades in the chassis are plugged in but are in standby mode, the Chassis 
Manager will drive fan speed at the minimum level. 


 
38    January 28, 2014 
 
6.5 Fan Failure 
Analysis shows that fan failures (tachometer speed below 20 percent of the 
requested speed for more than five minutes) are rare. 
6.5.1 Fan Failure Rate 
Failure rate for the fans is calculated using the following information: 
 Mean time between failures (MTBF) provided by the manufacturer is 50K hours at 
60OC 
 Failure rate improves two times for every 10OC reduction 
 Average outlet operating temperature is approximately 46OC, allowing for a 
greater than two times reduction 
 Annualized failure rate is therefore: 
o 6x10E-6 per chassis 
o 2.4x10E-5 per rack 
 Failures per year are therefore: 
o 0.05 for a chassis (one failure every 20 years) 
o 0.20 for a rack (one failure every 5 years) 
Data from the server vendor indicates that the most common cause of fan failure is a 
lubricant leak, which causes a fan to speed up for approximately a week before 
stopping when the lubricant is gone. Chassis management can monitor the speed of 
the fans and identify an algorithm to address speeds that are too fast or too slow. 
When a fan failure is detected, chassis management will speed up the remaining fans 
to compensate. 
6.5.2 Fan Repair 
Fan repair can generally be deferred because the blades can withstand operation 
with minimal airflow for a short period of time. (How long fan repair can be deferred 
will be determined when the repair experience, the airflow data, and the impact on 
other services are better understood.)  
If fan repair does become necessary, two technicians should be assigned to the task 
to minimize impact on the system. The fan tray assembly is mounted on a pinned 



Open Compute Project  Open CloudServer chassis specification  
http://opencompute.org    39 
 
hinge so that the full tray can be easily removed for repair, and both sides of the 
fans have wire screen guards for safety during service. 
The following steps describe how to replace a fan: 
1. Prepare all materials and a ladder if the fan is in the upper half of the rack. 
2. Open the fan door and disconnect the cable. 
3. Lift the fan tray off the hinge. 
4. Install the new fan tray onto the hinge. 
5. Plug in the cable. 
6. Close the fan door. 
Note that if chassis management turned the chassis attention LED on because of the 
fan failure, it will turn the LED off when it detects that the fans are operating 
correctly. 
6.6 Thermal Considerations for the Blade 
The blade must be able to operate at full-load capacity in all conditions described in 
this specification, including the upper and lower ambient temperatures, humidity 
levels, altitude levels, and available fan capability. If conditions are outside the 
prescribed limits, the blade should continue to operate as long as hardware and data 
are not at risk; if conditions are likely to cause damage, the blade should be shut 
down.  
For the largest possible operating range, the inlet temperature to the system should 
not drive blade shut down. The temperature of sensitive components should be 
individually monitored to prevent an unnecessary system shut down. 
Note that blade components frequently have an average operating temperature 
target that optimizes long-term reliability and an upper temperature limit to prevent 
hardware damage and maintain data integrity. Components should normally operate 
at the target, but they can operate at a higher temperature for a short time as long 
as they remain below the upper limit. 
The only thermal response the Chassis Manager gives is control of fan speed. While 
alerts are logged if a fan or a blade fails, the Chassis Manager does not request 



 
40    January 28, 2014 
 
blade shut downs. The blade is responsible for shut downs or throttling caused by 
high inlet temperature. 
7 Chassis Power 
Within the rack, chassis power limits are determined by the power-supply power 
limits under worst-case failure conditions. The power supplies cannot be run at more 
than 95 percent of maximum output capacity for long periods of time. The total 
blade power of a deployment therefore cannot exceed these values. The specific 
power cord and redundancy option (N+N or N+1) must also be considered when 
determining the final sizing.  
Table 8 shows the maximum blade power per chassis, the maximum AC cord load, 
and the AC power per rack for different rack loads. Note that additional power is 
required for the fans and also contributes to the AC load. 
Table 8. Maximum Blade Power per Chassis 
 
Max chassis 
blade load 
Max chassis 
AC cord load 
Rack AC power 
2 chassis 3 chassis 4 chassis 
N+N power 3500 W 4100 W 8.2 kW 12.3 kW 16.4 kW 
N+1 power 6000 W 6800 W 13.6 kW 20.4 kW 27.2 kW 
Table 9 shows the average power for blades given the chassis limits. Note that the 
lower the number of blades in the chassis, the higher the amount of power per 
chassis. Note also that there is a per-blade limit of 300W. For unequal loading (for 
example, when using storage servers), average power can be estimated by calculating 
the average power for the compute blades and associated storage blades.  
Table 9. Average Loading for Blades 



Open Compute Project  Open CloudServer chassis specification  
http://opencompute.org    41 
 
Redundancy  
level 
Max 
chassis 
blade load 
Blades per chassis, average power 
24 22 20 18 16 14 12 
N+N power 3500 W 146 W 159 W 175 W 194 W 219 W 250 W 292 W 
N+1 power 6000 W 250 W 273 W 300 W Above blade power limit 
8 Operating Environment 
Table 10 describes the environmental requirements in which the blades operate. 
Table 10. Operating Environment 
Specification  Requirement 
Inlet 
temperature 
Operating 
 50°F to 95°F (10°C to 35°C) at sea level 
 Maximum rate of change: 18°F (10°C)/hour 
 Allowable derating guideline of 1.6°F/1000ft (0.9°C/304m) above 
3000 ft 
Non-
operating 
 -40°F to 140°F (-40°C to 60°C) 
 Rate of change less than 36°F (20°C)/hour 
Humidity 
Operating 
 10% to 80% non-condensing   
 Maximum Rate of Change: 20% RH per hour 
 Maximum dewpoint: 85°F (29.4°C) 
Non-
operating 
 5% to 95% non-condensing 
 100.4°F (38°C) maximum wet bulb temperature 
Altitude 
Operating  10000ft (3050m) maximum 
 Rate of change less than 1500 ft/min (457m/min) 
Non-
operating 
 30000ft (9144m) maximum 
 Rate of change less than 1500 ft/min (457m/min) 
9 Safety and Compliance Documentation 
Table 11 lists the applicable compatibility and safety compliance documentation for 
the system. The server and/or the server components must comply with regulations 
and test procedures. 
Table 11. Documents Pertaining to EMC Safety 



 
42    January 28, 2014 
 
Document Details 
CISPR 22/EN 55022 
Class A & EN 55024 
Immunity requirements 
ANSI C63.4 – 2003 
“American National Standard for Methods of Measurement of Radio -Noise Emissions 
from Low-Voltage Electrical and Electronic Equipment in the Range of 9 kHz to 40 GHz.” 
American National Standards Institute (ANSI), 2003. 
UL 60950-1 
"Safety of Information Technology Equipment including Electrical Business 
Equipment, First Edition." Underwriters Laboratories, Inc., 2003.  
CSA C22.2 No. 
60950-1 
Canadian Standards Association, 2003. 
EN 55022 
"Limits and methods of measurement of radio interference characteristics of 
information technology equipment." European Committee for Electrotechnical 
Standardization (CENELEC), Third Edition, 1998. 
EN 55024 
“Information technology equipment - Immunity characteristics - Limits and 
methods of measurement.” European Committee for Electrotechnical 
Standardization (CENELEC), 1998. 
EN 60320-1 
"Appliance Couplers for Household and Similar General Purposes – Part: 
General Requirements" European Committee for Electrotechnical 
Standardization (CENELEC), 2001. 
IEC 60950-1: 2001 
“Safety of Information Technology Equipment - Safety - Part 1: General 
requirements”, First Edition, International Electrotechnical Commission, 2001.  
IEC 61000-4 
Sections 2 – 6, 11 
"Electromagnetic Compatibility (EMC) – Part 4: Testing and measurement 
techniques." International Electrotechnical Commission (IEC).  
C.I.S.P.R. Pub. 22 
"Limits and methods of measurement of radio interference characteristics of 
information technology equipment." International Special Committee on Radio 
Interference (C.I.S.P.R.), Third Edition, 1997. 
CFR 47, Part 15 
"Unintentional Radiators." Title 47 of the Code of Federal Regulations, Part 15, 
FCC Rules, Radio Frequency Devices, Subpart B. 
10 Shock and Vibration Requirements 
Table 12 lists the shock and vibration requirements for the system. These tests 
simulate normal transportation and handling conditions that the systems might 



Open Compute Project  Open CloudServer chassis specification  
http://opencompute.org    43 
 
encounter. 
Table 12. Shock and Vibration Requirements 
Specification 
(if applicable) Packaged/unpackaged Details Pass criteria 
ASTM D4728 
Assembled blades and 
chassis in rack, 
packaged 
 Air cushion transportation 
vibration test  
 Test to the normal rest 
surface (bottom side) for 
one hour of vertical 
direction (Z-axis) 
 Palletized 
 Normal function after 
test, no connector or 
mechanical damage 
 No component 
unseating 
NEBS GR-63-
CORE Issue 3, 
March 2006 
Assembled blades and 
chassis in rack, 
packaged 
 100mm (3.9in) drop on the 
normal rest surface 
(bottom side) 
 Perform two drops  
 Palletized 
 Normal function after 
test, no connector or 
mechanical damage 
 No component 
unseating 
Telcordia GR-
63-CORE, 
Section 5.4.2 
Rack level, unpackaged 
in a system 
 Operational 
 Swept sine, 0.1g, 5-100-
5Hz, 0.1 octave/min 
 Three axis 
 No errors in the 
running of the software 
Not 
applicable 
Rack level, unpackaged 
in a system 
 Operational 
 System fans at 20, 40, 60, 
80, and 100% duty cycle 
 All hard drives running 1K 
random writes and 64K 
sequential writes 
 Hard drive read/write 
errors within 1K random 
writes 
performance≧90% 
 64K sequential writes 
performance≧85% of 
peak performance 
Not 
applicable 
Blade level, 
unpackaged 
 Non-operational 
 Random vibration, 10-
500Hz, 1.87Grms 
 15min/side, six sides tested 
 No visible damage 
 Blade operational when 
tested after vibration 
Not 
applicable 
Blade level, 
unpackaged, 
0=blade18kg 
 Non-operational 
 Square wave 
 32g peak 
 6.85 m/s velocity change 
 Six sides 
 No visible damage 
 Blade operational when 
tested after shock 



 
44    January 28, 2014 
 
Specification 
(if applicable) Packaged/unpackaged Details Pass criteria 
Not 
applicable 
Blade level, 
unpackaged, 
18<blade34kg 
 Non-operational 
 Square wave 
 27g peak 
 5.97 m/s velocity change 
 Six sides 
 No visible damage 
 Blade operational when 
tested after shock 
Telcordia GR-
63-CORE, 
Section 5.3.1 
Blade level, packaged, 
0=blade15kg 
 Non-operational 
 1000mm drop 
 13 drops on sides, edges 
and corners 
 No visible damage 
 Blade operational when 
tested after all shocks 
Telcordia GR-
63-CORE, 
Section 5.3.1 
Blade level, packaged, 
15<blade20kg 
 Non-operational 
 800mm drop 
 13 drops on sides, edges 
and corners 
 No visible damage 
 Blade operational when 
tested after all shock 
Telcordia GR-
63-CORE, 
Section 5.3.1 
Blade level, packaged, 
20<blade30kg 
 Non-operational 
 600mm drop 
 13 drops on sides, edges 
and corners 
 No visible damage 
 Blade operational when 
tested after all shock 
Not 
applicable Blade level, packaged 
 Non-operational 
 1.146 Grams 
 Single blade package 
 15 minutes/side 
 6 sides tested 
 If bulk packaged 
 One hour on normal rest 
surface 
 No visible damage 
 Blade operational when 
tested after vibration 



Open Compute Project  Open CloudServer chassis specification  
http://opencompute.org    45 
 
Figure 30 shows an example of the results of a rack package vibration test.  
 
Figure 30. Rack package vibration test, air cushion transportation vibration test levels 
  


 
46    January 28, 2014 
 
11 Appendix: Commonly Used Acronyms 
This section provides definitions of acronyms used in the system specifications. 
ACPI – advanced configuration and 
power interface  
AHCI – advanced host controller 
interface 
AHJ – authority having jurisdiction 
ANSI – American National 
Standards Institute 
API – application programming 
interface 
ASHRAE – American Society of 
Heating, Refrigerating and Air 
Conditioning Engineers 
ASIC – application-specific 
integrated circuit 
BCD – binary-coded decimal 
BIOS – basic input/output system 
BMC – baseboard management 
controller 
CFM – cubic feet per minute 
(measure of volume flow rate) 
CM – Chassis Manager 
CMOS – complementary metal–
oxide–semiconductor 
COLO – co-location 
CTS – clear to send 
DCMI – Data Center Manageability 
Interface 
DDR3 – double data rate type 3  
DHCP – dynamic host 
configuration protocol 
DIMM – dual inline memory 
module  
DPC – DIMMs per memory channel  
DRAM – dynamic random access 
memory 
DSR – data set ready 
DTR – data terminal ready 
ECC – error-correcting code 
EEPROM - electrically erasable 
programmable read-only memory 
EIA – Electronic Industries Alliance 
EMC – electromagnetic 
compatibility 
EMI – electromagnetic interference 
FRU – field replaceable unit 
FTP – file transfer protocol 
GPIO – general purpose input 
output 
GUID – globally unique identifier 
HBI – high business intelligence 
HCK – Windows Hardware 
Certification Kit 
HMD – hardware monitoring 
device 
HT – hyperthreading 
I2C – inter-integrated circuit 
IBC – international building code 
IDE – integrated development 
environment 



Open Compute Project  Open CloudServer chassis specification  
http://opencompute.org    47 
 
IEC – International Electrotechnical 
Commission 
IOC – I/O controller 
IPMI – intelligent platform 
management interface 
IPsec – IP security 
ITPAC – IT pre-assembled 
components 
JBOD – “just a bunch of disks” 
KCS – keyboard controller style 
L2 – layer 2 
LAN – local area network 
LFF – large form factor 
LPC – low pin count 
LS – least significant 
LUN – logical unit number 
MAC – media access control 
MDC – modular data center 
containers 
MLC – multi-level call 
MTBF – mean time between 
failures  
MUX - multiplexer 
NIC – network interface card 
NUMA – non-uniform memory 
access 
OOB – out of band 
OSHA – Occupational Safety & 
Health Administration 
OTS – off the shelf 
PCB – printed circuit board 
PCIe – peripheral component 
interconnect express 
PCH – platform control hub 
PDB – power distribution 
backplane 
PDU – power distribution unit 
Ph-ph – phase to phase 
Ph-N – phase to neutral 
PNP – plug and play 
POST – power-on self-test 
PSU – power supply unit 
PWM – pulse-width modulation 
PXE – preboot execution 
environment 
QDR – quad data rate 
QFN – quad flat package no-lead 
QPI – Intel QuickPath Interconnect 
QSFP – Quad small form-factor 
pluggable 
RAID – redundant array of 
independent disks 
REST – representational state 
transfer 
RM – Rack Manager 
RMA – remote management agent 
ROC – RAID-on-chip controller 
RSS – receive-side scaling 
RTS – request to send 
RU – rack unit 
RxD – received data 
SAS – serial-attached small 
computer system interface (SCSI) 



 
48    January 28, 2014 
 
SATA – serial AT attachment 
SCK – serial clock 
SCSI – small computer system 
interface 
SDA – serial data signal 
SDR – sensor data record 
SFF – small form factor 
SFP - small form-factor pluggable  
SMBUS – systems management 
bus 
SMBIOS – systems management 
BIOS 
SOL – serial over LAN 
SPI – serial peripheral interface 
SSD – solid-state drive 
TB – tray backplane 
TDP – thermal design power 
TB – tray backplane 
TOR – top of rack 
TPM – trusted platform module 
TxD – transmit data 
U – rack unit 
UART – universal asynchronous 
receiver/transmitter 
UEFI – unified extensible firmware 
interface 
UL – Underwriters Laboratories 
UPS – uninterrupted power supply 
Vpp – voltage peak to peak 
WMI –Windows Management 
Interface 
 